(kicad_pcb
	(version 20241229)
	(generator "pcbnew")
	(generator_version "9.0")
	(general
		(thickness 1.294)
		(legacy_teardrops no)
	)
	(paper "A3")
	(title_block
		(title "Kintex 410T devboard")
		(date "2024-04-03")
		(rev "1.1.2")
		(comment 9 "footprints 551-556 of 975")
	)
	(layers
		(0 "F.Cu" mixed)
		(4 "In1.Cu" power)
		(6 "In2.Cu" power)
		(8 "In3.Cu" mixed)
		(10 "In4.Cu" power)
		(12 "In5.Cu" mixed)
		(14 "In6.Cu" power)
		(16 "In7.Cu" mixed)
		(18 "In8.Cu" power)
		(2 "B.Cu" mixed)
		(9 "F.Adhes" user "F.Adhesive")
		(11 "B.Adhes" user "B.Adhesive")
		(13 "F.Paste" user)
		(15 "B.Paste" user)
		(5 "F.SilkS" user "F.Silkscreen")
		(7 "B.SilkS" user "B.Silkscreen")
		(1 "F.Mask" user)
		(3 "B.Mask" user)
		(17 "Dwgs.User" user "User.Drawings")
		(19 "Cmts.User" user "User.Comments")
		(21 "Eco1.User" user "User.Eco1")
		(23 "Eco2.User" user "User.Eco2")
		(25 "Edge.Cuts" user)
		(27 "Margin" user)
		(31 "F.CrtYd" user "F.Courtyard")
		(29 "B.CrtYd" user "B.Courtyard")
		(35 "F.Fab" user)
		(33 "B.Fab" user)
	)
	(footprint "antmicro-footprints:C_0402_1005Metric"
		(layer "B.Cu")
		(at 207 137.52)
		(descr "Capacitor SMD 0402")
		(tags "capacitor SMD 0402")
		(property "Reference" "C35"
			(at 1.45 -0.475 180)
			(layer "B.SilkS")
			(effects
				(font
					(size 0.7 0.7)
					(thickness 0.15)
				)
				(justify left bottom mirror)
			)
		)
		(property "Value" "C_100n_0402"
			(at 0 -1.169 180)
			(layer "B.Fab")
			(effects
				(font
					(size 0.7 0.7)
					(thickness 0.15)
				)
				(justify left bottom mirror)
			)
		)
		(property "Description" "SMD Multilayer Ceramic Capacitor, 0.1 µF, 50 V, 0402 [1005 Metric], ± 10%, X5R, GRM Series"
			(at 0 0 0)
			(layer "F.Fab")
			(hide yes)
			(effects
				(font
					(size 1.27 1.27)
					(thickness 0.15)
				)
			)
		)
		(property "Author" "Antmicro"
			(at 0 0 0)
			(layer "B.Fab")
			(hide yes)
			(effects
				(font
					(size 1 1)
					(thickness 0.15)
				)
				(justify mirror)
			)
		)
		(property "Dielectric" "X5R"
			(at 0 0 0)
			(layer "B.Fab")
			(hide yes)
			(effects
				(font
					(size 1 1)
					(thickness 0.15)
				)
				(justify mirror)
			)
		)
		(property "License" "Apache-2.0"
			(at 0 0 0)
			(layer "B.Fab")
			(hide yes)
			(effects
				(font
					(size 1 1)
					(thickness 0.15)
				)
				(justify mirror)
			)
		)
		(property "MPN" "GRM155R61H104KE14D"
			(at 0 0 0)
			(layer "B.Fab")
			(hide yes)
			(effects
				(font
					(size 1 1)
					(thickness 0.15)
				)
				(justify mirror)
			)
		)
		(property "Manufacturer" "Murata"
			(at 0 0 0)
			(layer "B.Fab")
			(hide yes)
			(effects
				(font
					(size 1 1)
					(thickness 0.15)
				)
				(justify mirror)
			)
		)
		(property "Val" "100n"
			(at 0 0 0)
			(layer "B.Fab")
			(hide yes)
			(effects
				(font
					(size 1 1)
					(thickness 0.15)
				)
				(justify mirror)
			)
		)
		(property "Voltage" "50V"
			(at 0 0 0)
			(layer "B.Fab")
			(hide yes)
			(effects
				(font
					(size 1 1)
					(thickness 0.15)
				)
				(justify mirror)
			)
		)
		(sheetname "FPGA Bank 12 & 13")
		(sheetfile "fpga-bank-12-13.kicad_sch")
		(attr smd)
		(fp_rect
			(start -0.925 0.47)
			(end 0.925 -0.47)
			(stroke
				(width 0.05)
				(type default)
			)
			(fill no)
			(layer "B.CrtYd")
		)
		(fp_line
			(start -0.494 -0.248)
			(end -0.494 0.25)
			(stroke
				(width 0.15)
				(type solid)
			)
			(layer "B.Fab")
		)
		(fp_line
			(start -0.494 0.25)
			(end 0.504 0.25)
			(stroke
				(width 0.15)
				(type solid)
			)
			(layer "B.Fab")
		)
		(fp_line
			(start 0.504 -0.248)
			(end -0.494 -0.248)
			(stroke
				(width 0.15)
				(type solid)
			)
			(layer "B.Fab")
		)
		(fp_line
			(start 0.504 0.25)
			(end 0.504 -0.248)
			(stroke
				(width 0.15)
				(type solid)
			)
			(layer "B.Fab")
		)
		(pad "1" smd roundrect
			(at -0.48 0)
			(size 0.59 0.64)
			(layers "B.Cu" "B.Mask" "B.Paste")
			(roundrect_rratio 0.25)
			(net 1 "GND")
			(pintype "passive")
		)
		(pad "2" smd roundrect
			(at 0.48 0)
			(size 0.59 0.64)
			(layers "B.Cu" "B.Mask" "B.Paste")
			(roundrect_rratio 0.25)
			(net 24 "+3V3")
			(pintype "passive")
		)
	)
	(footprint "antmicro-footprints:R_0402_1005Metric"
		(layer "B.Cu")
		(at 223.586 149.2 180)
		(descr "Resistor SMD 0402")
		(tags "resistor SMD 0402")
		(property "Reference" "R227"
			(at -1.839 -2.35 0)
			(layer "B.SilkS")
			(effects
				(font
					(size 0.7 0.7)
					(thickness 0.15)
				)
				(justify left bottom mirror)
			)
		)
		(property "Value" "R_2k2_0402"
			(at 0 -1.4 0)
			(layer "B.Fab")
			(effects
				(font
					(size 0.7 0.7)
					(thickness 0.15)
				)
				(justify left bottom mirror)
			)
		)
		(property "Description" "SMD Chip Resistor, 2.2 kohm, ± 1%, 62.5 mW, 0402 [1005 Metric], Thick Film, General Purpose"
			(at 0 0 180)
			(layer "F.Fab")
			(hide yes)
			(effects
				(font
					(size 1.27 1.27)
					(thickness 0.15)
				)
			)
		)
		(property "Author" "Antmicro"
			(at 447.172 298.4 0)
			(layer "B.Fab")
			(hide yes)
			(effects
				(font
					(size 1 1)
					(thickness 0.15)
				)
				(justify mirror)
			)
		)
		(property "DNP" "DNP"
			(at 447.172 298.4 0)
			(layer "B.Fab")
			(hide yes)
			(effects
				(font
					(size 1 1)
					(thickness 0.15)
				)
				(justify mirror)
			)
		)
		(property "License" "Apache-2.0"
			(at 447.172 298.4 0)
			(layer "B.Fab")
			(hide yes)
			(effects
				(font
					(size 1 1)
					(thickness 0.15)
				)
				(justify mirror)
			)
		)
		(property "MPN" "CR0402-FX-2201GLF"
			(at 447.172 298.4 0)
			(layer "B.Fab")
			(hide yes)
			(effects
				(font
					(size 1 1)
					(thickness 0.15)
				)
				(justify mirror)
			)
		)
		(property "Manufacturer" "Bourns"
			(at 447.172 298.4 0)
			(layer "B.Fab")
			(hide yes)
			(effects
				(font
					(size 1 1)
					(thickness 0.15)
				)
				(justify mirror)
			)
		)
		(property "Tolerance" "1%"
			(at 447.172 298.4 0)
			(layer "B.Fab")
			(hide yes)
			(effects
				(font
					(size 1 1)
					(thickness 0.15)
				)
				(justify mirror)
			)
		)
		(property "Val" "2k2"
			(at 447.172 298.4 0)
			(layer "B.Fab")
			(hide yes)
			(effects
				(font
					(size 1 1)
					(thickness 0.15)
				)
				(justify mirror)
			)
		)
		(property "dnp" ""
			(at 447.172 298.4 0)
			(layer "B.Fab")
			(hide yes)
			(effects
				(font
					(size 1 1)
					(thickness 0.15)
				)
				(justify mirror)
			)
		)
		(property "exclude_from_bom" ""
			(at 447.172 298.4 0)
			(layer "B.Fab")
			(hide yes)
			(effects
				(font
					(size 1 1)
					(thickness 0.15)
				)
				(justify mirror)
			)
		)
		(sheetname "HDMI + Ethernet")
		(sheetfile "hdmi-ethernet.kicad_sch")
		(attr smd exclude_from_bom)
		(fp_rect
			(start -0.925 0.47)
			(end 0.925 -0.47)
			(stroke
				(width 0.05)
				(type default)
			)
			(fill no)
			(layer "B.CrtYd")
		)
		(fp_rect
			(start -0.5 0.25)
			(end 0.5 -0.25)
			(stroke
				(width 0.15)
				(type solid)
			)
			(fill no)
			(layer "B.Fab")
		)
		(pad "1" smd roundrect
			(at -0.48 0 180)
			(size 0.59 0.64)
			(layers "B.Cu" "B.Mask" "B.Paste")
			(roundrect_rratio 0.25)
			(net 946 "/HDMI + Ethernet/ETH_PHY_RXDO")
			(pintype "passive")
		)
		(pad "2" smd roundrect
			(at 0.48 0 180)
			(size 0.59 0.64)
			(layers "B.Cu" "B.Mask" "B.Paste")
			(roundrect_rratio 0.25)
			(net 1 "GND")
			(pintype "passive")
		)
	)
	(footprint "antmicro-footprints:C_0201"
		(layer "B.Cu")
		(at 189.8 121.5 180)
		(descr "Capacitor SMD 0201")
		(tags "capacitor SMD 0201")
		(property "Reference" "C148"
			(at -22.625 29.63 0)
			(layer "B.SilkS")
			(effects
				(font
					(size 0.7 0.7)
					(thickness 0.15)
				)
				(justify left bottom mirror)
			)
		)
		(property "Value" "C_100n_0201"
			(at 0 -1.4 0)
			(layer "B.Fab")
			(effects
				(font
					(size 0.7 0.7)
					(thickness 0.15)
				)
				(justify left bottom mirror)
			)
		)
		(property "Description" "SMD Multilayer Ceramic Capacitor, 0.1 µF, 6.3 V, 0201 [0603 Metric], ± 10%, X6S, CC Series"
			(at 0 0 180)
			(layer "F.Fab")
			(hide yes)
			(effects
				(font
					(size 1.27 1.27)
					(thickness 0.15)
				)
			)
		)
		(property "Author" "Antmicro"
			(at 379.6 243 0)
			(layer "B.Fab")
			(hide yes)
			(effects
				(font
					(size 1 1)
					(thickness 0.15)
				)
				(justify mirror)
			)
		)
		(property "Dielectric" ""
			(at 379.6 243 0)
			(layer "B.Fab")
			(hide yes)
			(effects
				(font
					(size 1 1)
					(thickness 0.15)
				)
				(justify mirror)
			)
		)
		(property "License" "Apache-2.0"
			(at 379.6 243 0)
			(layer "B.Fab")
			(hide yes)
			(effects
				(font
					(size 1 1)
					(thickness 0.15)
				)
				(justify mirror)
			)
		)
		(property "MPN" "CC0201KRX6S5BB104"
			(at 379.6 243 0)
			(layer "B.Fab")
			(hide yes)
			(effects
				(font
					(size 1 1)
					(thickness 0.15)
				)
				(justify mirror)
			)
		)
		(property "Manufacturer" "YAGEO"
			(at 379.6 243 0)
			(layer "B.Fab")
			(hide yes)
			(effects
				(font
					(size 1 1)
					(thickness 0.15)
				)
				(justify mirror)
			)
		)
		(property "Val" "100n"
			(at 379.6 243 0)
			(layer "B.Fab")
			(hide yes)
			(effects
				(font
					(size 1 1)
					(thickness 0.15)
				)
				(justify mirror)
			)
		)
		(property "Voltage" ""
			(at 379.6 243 0)
			(layer "B.Fab")
			(hide yes)
			(effects
				(font
					(size 1 1)
					(thickness 0.15)
				)
				(justify mirror)
			)
		)
		(sheetname "FPGA supply")
		(sheetfile "fpga-supply.kicad_sch")
		(attr smd)
		(fp_rect
			(start -0.7 0.35)
			(end 0.7 -0.35)
			(stroke
				(width 0.05)
				(type default)
			)
			(fill no)
			(layer "B.CrtYd")
		)
		(fp_rect
			(start 0.3 -0.15)
			(end -0.301 0.149)
			(stroke
				(width 0.15)
				(type solid)
			)
			(fill no)
			(layer "B.Fab")
		)
		(pad "" smd roundrect
			(at -0.349 0.002 180)
			(size 0.318 0.36)
			(layers "B.Paste")
			(roundrect_rratio 0.25)
		)
		(pad "" smd roundrect
			(at 0.341 0.002 180)
			(size 0.318 0.36)
			(layers "B.Paste")
			(roundrect_rratio 0.25)
		)
		(pad "1" smd roundrect
			(at -0.321 0.002 180)
			(size 0.46 0.4)
			(layers "B.Cu" "B.Mask")
			(roundrect_rratio 0.25)
			(net 1 "GND")
			(pintype "passive")
		)
		(pad "2" smd roundrect
			(at 0.32 0.002 180)
			(size 0.46 0.4)
			(layers "B.Cu" "B.Mask")
			(roundrect_rratio 0.25)
			(net 8 "+1V2_MGTAVTT")
			(pintype "passive")
		)
	)
	(footprint "antmicro-footprints:R_0402_1005Metric"
		(layer "B.Cu")
		(at 198.491252 92.55)
		(descr "Resistor SMD 0402")
		(tags "resistor SMD 0402")
		(property "Reference" "R210"
			(at 1.483748 -4.6 180)
			(layer "B.SilkS")
			(effects
				(font
					(size 0.7 0.7)
					(thickness 0.15)
				)
				(justify left bottom mirror)
			)
		)
		(property "Value" "R_2k2_0402"
			(at 0 -1.4 180)
			(layer "B.Fab")
			(effects
				(font
					(size 0.7 0.7)
					(thickness 0.15)
				)
				(justify left bottom mirror)
			)
		)
		(property "Description" "SMD Chip Resistor, 2.2 kohm, ± 1%, 62.5 mW, 0402 [1005 Metric], Thick Film, General Purpose"
			(at 0 0 0)
			(layer "F.Fab")
			(hide yes)
			(effects
				(font
					(size 1.27 1.27)
					(thickness 0.15)
				)
			)
		)
		(property "Author" "Antmicro"
			(at 0 0 0)
			(layer "B.Fab")
			(hide yes)
			(effects
				(font
					(size 1 1)
					(thickness 0.15)
				)
				(justify mirror)
			)
		)
		(property "DNP" "DNP"
			(at 0 0 0)
			(layer "B.Fab")
			(hide yes)
			(effects
				(font
					(size 1 1)
					(thickness 0.15)
				)
				(justify mirror)
			)
		)
		(property "License" "Apache-2.0"
			(at 0 0 0)
			(layer "B.Fab")
			(hide yes)
			(effects
				(font
					(size 1 1)
					(thickness 0.15)
				)
				(justify mirror)
			)
		)
		(property "MPN" "CR0402-FX-2201GLF"
			(at 0 0 0)
			(layer "B.Fab")
			(hide yes)
			(effects
				(font
					(size 1 1)
					(thickness 0.15)
				)
				(justify mirror)
			)
		)
		(property "Manufacturer" "Bourns"
			(at 0 0 0)
			(layer "B.Fab")
			(hide yes)
			(effects
				(font
					(size 1 1)
					(thickness 0.15)
				)
				(justify mirror)
			)
		)
		(property "Tolerance" "1%"
			(at 0 0 0)
			(layer "B.Fab")
			(hide yes)
			(effects
				(font
					(size 1 1)
					(thickness 0.15)
				)
				(justify mirror)
			)
		)
		(property "Val" "2k2"
			(at 0 0 0)
			(layer "B.Fab")
			(hide yes)
			(effects
				(font
					(size 1 1)
					(thickness 0.15)
				)
				(justify mirror)
			)
		)
		(property "dnp" ""
			(at 0 0 0)
			(layer "B.Fab")
			(hide yes)
			(effects
				(font
					(size 1 1)
					(thickness 0.15)
				)
				(justify mirror)
			)
		)
		(property "exclude_from_bom" ""
			(at 0 0 0)
			(layer "B.Fab")
			(hide yes)
			(effects
				(font
					(size 1 1)
					(thickness 0.15)
				)
				(justify mirror)
			)
		)
		(sheetname "HDMI + Ethernet")
		(sheetfile "hdmi-ethernet.kicad_sch")
		(attr smd exclude_from_bom)
		(fp_rect
			(start -0.925 0.47)
			(end 0.925 -0.47)
			(stroke
				(width 0.05)
				(type default)
			)
			(fill no)
			(layer "B.CrtYd")
		)
		(fp_rect
			(start -0.5 0.25)
			(end 0.5 -0.25)
			(stroke
				(width 0.15)
				(type solid)
			)
			(fill no)
			(layer "B.Fab")
		)
		(pad "1" smd roundrect
			(at -0.48 0)
			(size 0.59 0.64)
			(layers "B.Cu" "B.Mask" "B.Paste")
			(roundrect_rratio 0.25)
			(net 504 "/FPGA Bank 16 & 17/GBE_RGMII.RXD2")
			(pintype "passive")
		)
		(pad "2" smd roundrect
			(at 0.48 0)
			(size 0.59 0.64)
			(layers "B.Cu" "B.Mask" "B.Paste")
			(roundrect_rratio 0.25)
			(net 1 "GND")
			(pintype "passive")
		)
	)
	(footprint "antmicro-footprints:C_0603_1608Metric"
		(layer "B.Cu")
		(at 200 126.1 -90)
		(descr "Capacitor SMD 0603")
		(tags "capacitor 0603")
		(property "Reference" "C377"
			(at -31.3 -25.75 90)
			(layer "B.SilkS")
			(effects
				(font
					(size 0.7 0.7)
					(thickness 0.15)
				)
				(justify left bottom mirror)
			)
		)
		(property "Value" "C_47u_0603"
			(at 0 -1.6 90)
			(layer "B.Fab")
			(effects
				(font
					(size 0.7 0.7)
					(thickness 0.15)
				)
				(justify left bottom mirror)
			)
		)
		(property "Description" "SMD Multilayer Ceramic Capacitor, 47 µF, 6.3 V, 0603 [1608 Metric], ± 20%, X5R, GRM Series"
			(at 0 0 270)
			(layer "F.Fab")
			(hide yes)
			(effects
				(font
					(size 1.27 1.27)
					(thickness 0.15)
				)
			)
		)
		(property "Author" "Antmicro"
			(at 73.9 326.1 0)
			(layer "B.Fab")
			(hide yes)
			(effects
				(font
					(size 1 1)
					(thickness 0.15)
				)
				(justify mirror)
			)
		)
		(property "Dielectric" ""
			(at 73.9 326.1 0)
			(layer "B.Fab")
			(hide yes)
			(effects
				(font
					(size 1 1)
					(thickness 0.15)
				)
				(justify mirror)
			)
		)
		(property "License" "Apache-2.0"
			(at 73.9 326.1 0)
			(layer "B.Fab")
			(hide yes)
			(effects
				(font
					(size 1 1)
					(thickness 0.15)
				)
				(justify mirror)
			)
		)
		(property "MPN" "GRM188R60J476ME15D"
			(at 73.9 326.1 0)
			(layer "B.Fab")
			(hide yes)
			(effects
				(font
					(size 1 1)
					(thickness 0.15)
				)
				(justify mirror)
			)
		)
		(property "Manufacturer" "Murata"
			(at 73.9 326.1 0)
			(layer "B.Fab")
			(hide yes)
			(effects
				(font
					(size 1 1)
					(thickness 0.15)
				)
				(justify mirror)
			)
		)
		(property "Val" "47u"
			(at 73.9 326.1 0)
			(layer "B.Fab")
			(hide yes)
			(effects
				(font
					(size 1 1)
					(thickness 0.15)
				)
				(justify mirror)
			)
		)
		(property "Voltage" ""
			(at 73.9 326.1 0)
			(layer "B.Fab")
			(hide yes)
			(effects
				(font
					(size 1 1)
					(thickness 0.15)
				)
				(justify mirror)
			)
		)
		(sheetname "FPGA supply")
		(sheetfile "fpga-supply.kicad_sch")
		(attr smd)
		(fp_line
			(start -0.15 0.4)
			(end 0.15 0.4)
			(stroke
				(width 0.15)
				(type solid)
			)
			(layer "B.SilkS")
		)
		(fp_line
			(start -0.15 -0.4)
			(end 0.15 -0.4)
			(stroke
				(width 0.15)
				(type solid)
			)
			(layer "B.SilkS")
		)
		(fp_rect
			(start -1.25 0.65)
			(end 1.25 -0.65)
			(stroke
				(width 0.05)
				(type solid)
			)
			(fill no)
			(layer "B.CrtYd")
		)
		(fp_rect
			(start -0.8 0.4)
			(end 0.8 -0.4)
			(stroke
				(width 0.15)
				(type solid)
			)
			(fill no)
			(layer "B.Fab")
		)
		(pad "1" smd roundrect
			(at -0.7 0 270)
			(size 0.8 1)
			(layers "B.Cu" "B.Mask" "B.Paste")
			(roundrect_rratio 0.2)
			(net 1 "GND")
			(pintype "passive")
		)
		(pad "2" smd roundrect
			(at 0.7 0 270)
			(size 0.8 1)
			(layers "B.Cu" "B.Mask" "B.Paste")
			(roundrect_rratio 0.2)
			(net 650 "+1V0")
			(pintype "passive")
		)
	)
	(footprint "antmicro-footprints:C_0201"
		(layer "B.Cu")
		(at 192.3 128.2 -45)
		(descr "Capacitor SMD 0201")
		(tags "capacitor SMD 0201")
		(property "Reference" "C97"
			(at -4.224963 -35.72657 315)
			(unlocked yes)
			(layer "B.SilkS")
			(effects
				(font
					(size 0.7 0.7)
					(thickness 0.15)
				)
				(justify left bottom mirror)
			)
		)
		(property "Value" "C_100n_0201"
			(at 0 -1.399999 135)
			(layer "B.Fab")
			(effects
				(font
					(size 0.7 0.7)
					(thickness 0.15)
				)
				(justify left bottom mirror)
			)
		)
		(property "Description" "SMD Multilayer Ceramic Capacitor, 0.1 µF, 6.3 V, 0201 [0603 Metric], ± 10%, X6S, CC Series"
			(at 0 0 315)
			(layer "F.Fab")
			(hide yes)
			(effects
				(font
					(size 1.27 1.27)
					(thickness 0.15)
				)
			)
		)
		(property "Author" "Antmicro"
			(at -34.327723 173.525544 0)
			(layer "B.Fab")
			(hide yes)
			(effects
				(font
					(size 1 1)
					(thickness 0.15)
				)
				(justify mirror)
			)
		)
		(property "Dielectric" ""
			(at -34.327723 173.525544 0)
			(layer "B.Fab")
			(hide yes)
			(effects
				(font
					(size 1 1)
					(thickness 0.15)
				)
				(justify mirror)
			)
		)
		(property "License" "Apache-2.0"
			(at -34.327723 173.525544 0)
			(layer "B.Fab")
			(hide yes)
			(effects
				(font
					(size 1 1)
					(thickness 0.15)
				)
				(justify mirror)
			)
		)
		(property "MPN" "CC0201KRX6S5BB104"
			(at -34.327723 173.525544 0)
			(layer "B.Fab")
			(hide yes)
			(effects
				(font
					(size 1 1)
					(thickness 0.15)
				)
				(justify mirror)
			)
		)
		(property "Manufacturer" "YAGEO"
			(at -34.327723 173.525544 0)
			(layer "B.Fab")
			(hide yes)
			(effects
				(font
					(size 1 1)
					(thickness 0.15)
				)
				(justify mirror)
			)
		)
		(property "Val" "100n"
			(at -34.327723 173.525544 0)
			(layer "B.Fab")
			(hide yes)
			(effects
				(font
					(size 1 1)
					(thickness 0.15)
				)
				(justify mirror)
			)
		)
		(property "Voltage" ""
			(at -34.327723 173.525544 0)
			(layer "B.Fab")
			(hide yes)
			(effects
				(font
					(size 1 1)
					(thickness 0.15)
				)
				(justify mirror)
			)
		)
		(sheetname "FPGA supply")
		(sheetfile "fpga-supply.kicad_sch")
		(attr smd)
		(fp_poly
			(pts
				(xy -0.7 0.35) (xy 0.7 0.35) (xy 0.7 -0.35) (xy -0.7 -0.35)
			)
			(stroke
				(width 0.05)
				(type default)
			)
			(fill no)
			(layer "B.CrtYd")
		)
		(fp_poly
			(pts
				(xy 0.3 -0.15) (xy -0.301 -0.15) (xy -0.301 0.149) (xy 0.3 0.149)
			)
			(stroke
				(width 0.15)
				(type solid)
			)
			(fill no)
			(layer "B.Fab")
		)
		(pad "" smd roundrect
			(at -0.349 0.002 315)
			(size 0.318 0.36)
			(layers "B.Paste")
			(roundrect_rratio 0.25)
		)
		(pad "" smd roundrect
			(at 0.341 0.002 315)
			(size 0.318 0.36)
			(layers "B.Paste")
			(roundrect_rratio 0.25)
		)
		(pad "1" smd roundrect
			(at -0.321 0.002 315)
			(size 0.46 0.4)
			(layers "B.Cu" "B.Mask")
			(roundrect_rratio 0.25)
			(net 6 "+1V0_MGTAVCC")
			(pintype "passive")
		)
		(pad "2" smd roundrect
			(at 0.32 0.002 315)
			(size 0.46 0.4)
			(layers "B.Cu" "B.Mask")
			(roundrect_rratio 0.25)
			(net 1 "GND")
			(pintype "passive")
		)
	)
)
